(kicad_pcb
	(version 20260206)
	(generator "pcbnew")
	(generator_version "10.0")
	(general
		(thickness 1.6)
		(legacy_teardrops no)
	)
	(paper "A4")
	(title_block
		(title "04192023_DAF0TMB3IC0_F0TG_MB_C_brd_V02_OCP.brd")
		(comment 1 "Grand Teton / footprints 4046-4051 of 8354")
	)
	(layers
		(0 "F.Cu" signal "TOP")
		(4 "In1.Cu" signal "GND")
		(6 "In2.Cu" signal "IN1")
		(8 "In3.Cu" signal "GND1")
		(10 "In4.Cu" signal "IN2")
		(12 "In5.Cu" signal "GND2")
		(14 "In6.Cu" signal "IN3")
		(16 "In7.Cu" signal "GND3")
		(18 "In8.Cu" signal "VCC")
		(20 "In9.Cu" signal "VCC1")
		(22 "In10.Cu" signal "GND4")
		(24 "In11.Cu" signal "IN4")
		(26 "In12.Cu" signal "GND5")
		(28 "In13.Cu" signal "IN5")
		(30 "In14.Cu" signal "GND6")
		(32 "In15.Cu" signal "IN6")
		(34 "In16.Cu" signal "GND7")
		(2 "B.Cu" signal "BOTTOM")
		(9 "F.Adhes" user "F.Adhesive")
		(11 "B.Adhes" user "B.Adhesive")
		(13 "F.Paste" user "Package Geometry/Pastemask Top")
		(15 "B.Paste" user "Package Geometry/Pastemask Bottom")
		(5 "F.SilkS" user "Ref Des/Silkscreen Top")
		(7 "B.SilkS" user "Ref Des/Silkscreen Bottom")
		(1 "F.Mask" user "Board Geometry/Soldermask Top")
		(3 "B.Mask" user "Board Geometry/Soldermask Bottom")
		(17 "Dwgs.User" user "User.Drawings")
		(19 "Cmts.User" user "User.Comments")
		(21 "Eco1.User" user "User.Eco1")
		(23 "Eco2.User" user "User.Eco2")
		(25 "Edge.Cuts" user "Board Geometry/Outline")
		(27 "Margin" user)
		(31 "F.CrtYd" user "Package Geometry/Place Bound Top")
		(29 "B.CrtYd" user "Package Geometry/Place Bound Bottom")
		(35 "F.Fab" user "Ref Des/Assembly Top")
		(33 "B.Fab" user "Ref Des/Assembly Bottom")
	)
	(footprint ""
		(layer "F.Cu")
		(at 98.314764 -178.0413 -90)
		(property "Reference" "PR197"
			(at 0 0 270)
			(layer "F.SilkS")
			(hide yes)
			(effects
				(font
					(size 1.27 1.27)
				)
			)
		)
		(property "Value" ""
			(at 0 0 270)
			(layer "F.Fab")
			(effects
				(font
					(size 1.27 1.27)
				)
			)
		)
		(duplicate_pad_numbers_are_jumpers no)
		(fp_line
			(start -0.7874 0.4064)
			(end -0.7874 -0.4064)
			(stroke
				(width 0.1524)
				(type default)
			)
			(layer "F.SilkS")
		)
		(fp_line
			(start 0.7874 0.4064)
			(end -0.7874 0.4064)
			(stroke
				(width 0.1524)
				(type default)
			)
			(layer "F.SilkS")
		)
		(fp_line
			(start -0.7874 -0.4064)
			(end 0.7874 -0.4064)
			(stroke
				(width 0.1524)
				(type default)
			)
			(layer "F.SilkS")
		)
		(fp_line
			(start 0.7874 -0.4064)
			(end 0.7874 0.4064)
			(stroke
				(width 0.1524)
				(type default)
			)
			(layer "F.SilkS")
		)
		(fp_line
			(start -0.67945 0.3048)
			(end -0.67945 -0.305054)
			(stroke
				(width 0.1)
				(type default)
			)
			(layer "F.Fab")
		)
		(fp_line
			(start -0.12065 0.3048)
			(end -0.67945 0.3048)
			(stroke
				(width 0.1)
				(type default)
			)
			(layer "F.Fab")
		)
		(fp_line
			(start 0.120396 0.3048)
			(end 0.120396 0.2794)
			(stroke
				(width 0.1)
				(type default)
			)
			(layer "F.Fab")
		)
		(fp_line
			(start 0.67945 0.3048)
			(end 0.120396 0.3048)
			(stroke
				(width 0.1)
				(type default)
			)
			(layer "F.Fab")
		)
		(fp_line
			(start -0.12065 0.2794)
			(end -0.12065 0.3048)
			(stroke
				(width 0.1)
				(type default)
			)
			(layer "F.Fab")
		)
		(fp_line
			(start 0.120396 0.2794)
			(end -0.12065 0.2794)
			(stroke
				(width 0.1)
				(type default)
			)
			(layer "F.Fab")
		)
		(fp_line
			(start -0.12065 -0.2794)
			(end 0.12065 -0.2794)
			(stroke
				(width 0.1)
				(type default)
			)
			(layer "F.Fab")
		)
		(fp_line
			(start 0.12065 -0.2794)
			(end 0.12065 -0.3048)
			(stroke
				(width 0.1)
				(type default)
			)
			(layer "F.Fab")
		)
		(fp_line
			(start 0.12065 -0.3048)
			(end 0.67945 -0.3048)
			(stroke
				(width 0.1)
				(type default)
			)
			(layer "F.Fab")
		)
		(fp_line
			(start 0.67945 -0.3048)
			(end 0.67945 0.3048)
			(stroke
				(width 0.1)
				(type default)
			)
			(layer "F.Fab")
		)
		(fp_line
			(start -0.67945 -0.305054)
			(end -0.12065 -0.305054)
			(stroke
				(width 0.1)
				(type default)
			)
			(layer "F.Fab")
		)
		(fp_line
			(start -0.12065 -0.305054)
			(end -0.12065 -0.2794)
			(stroke
				(width 0.1)
				(type default)
			)
			(layer "F.Fab")
		)
		(pad "1" smd circle
			(at -0.40005 0 270)
			(size 0 0)
			(layers "F.Cu" "F.Mask" "F.Paste")
			(net "SW_PVDDCR_CPU0_P1_BOOT3")
		)
		(pad "2" smd circle
			(at 0.40005 0 270)
			(size 0 0)
			(layers "F.Cu" "F.Mask" "F.Paste")
			(net "SW_PVDDCR_CPU0_P1_BOOT3_RC")
		)
	)
	(footprint ""
		(layer "F.Cu")
		(at 178.47183 -157.508194 -90)
		(property "Reference" "R495"
			(at 0 0 270)
			(layer "F.SilkS")
			(hide yes)
			(effects
				(font
					(size 1.27 1.27)
				)
			)
		)
		(property "Value" ""
			(at 0 0 270)
			(layer "F.Fab")
			(effects
				(font
					(size 1.27 1.27)
				)
			)
		)
		(duplicate_pad_numbers_are_jumpers no)
		(fp_line
			(start -0.7874 0.4064)
			(end -0.7874 -0.4064)
			(stroke
				(width 0.1524)
				(type default)
			)
			(layer "F.SilkS")
		)
		(fp_line
			(start 0.7874 0.4064)
			(end -0.7874 0.4064)
			(stroke
				(width 0.1524)
				(type default)
			)
			(layer "F.SilkS")
		)
		(fp_line
			(start -0.7874 -0.4064)
			(end 0.7874 -0.4064)
			(stroke
				(width 0.1524)
				(type default)
			)
			(layer "F.SilkS")
		)
		(fp_line
			(start 0.7874 -0.4064)
			(end 0.7874 0.4064)
			(stroke
				(width 0.1524)
				(type default)
			)
			(layer "F.SilkS")
		)
		(fp_line
			(start -0.67945 0.3048)
			(end -0.67945 -0.305054)
			(stroke
				(width 0.1)
				(type default)
			)
			(layer "F.Fab")
		)
		(fp_line
			(start -0.12065 0.3048)
			(end -0.67945 0.3048)
			(stroke
				(width 0.1)
				(type default)
			)
			(layer "F.Fab")
		)
		(fp_line
			(start 0.120396 0.3048)
			(end 0.120396 0.2794)
			(stroke
				(width 0.1)
				(type default)
			)
			(layer "F.Fab")
		)
		(fp_line
			(start 0.67945 0.3048)
			(end 0.120396 0.3048)
			(stroke
				(width 0.1)
				(type default)
			)
			(layer "F.Fab")
		)
		(fp_line
			(start -0.12065 0.2794)
			(end -0.12065 0.3048)
			(stroke
				(width 0.1)
				(type default)
			)
			(layer "F.Fab")
		)
		(fp_line
			(start 0.120396 0.2794)
			(end -0.12065 0.2794)
			(stroke
				(width 0.1)
				(type default)
			)
			(layer "F.Fab")
		)
		(fp_line
			(start -0.12065 -0.2794)
			(end 0.12065 -0.2794)
			(stroke
				(width 0.1)
				(type default)
			)
			(layer "F.Fab")
		)
		(fp_line
			(start 0.12065 -0.2794)
			(end 0.12065 -0.3048)
			(stroke
				(width 0.1)
				(type default)
			)
			(layer "F.Fab")
		)
		(fp_line
			(start 0.12065 -0.3048)
			(end 0.67945 -0.3048)
			(stroke
				(width 0.1)
				(type default)
			)
			(layer "F.Fab")
		)
		(fp_line
			(start 0.67945 -0.3048)
			(end 0.67945 0.3048)
			(stroke
				(width 0.1)
				(type default)
			)
			(layer "F.Fab")
		)
		(fp_line
			(start -0.67945 -0.305054)
			(end -0.12065 -0.305054)
			(stroke
				(width 0.1)
				(type default)
			)
			(layer "F.Fab")
		)
		(fp_line
			(start -0.12065 -0.305054)
			(end -0.12065 -0.2794)
			(stroke
				(width 0.1)
				(type default)
			)
			(layer "F.Fab")
		)
		(pad "1" smd circle
			(at -0.40005 0 270)
			(size 0 0)
			(layers "F.Cu" "F.Mask" "F.Paste")
			(net "PVDD18_S5_P0")
		)
		(pad "2" smd circle
			(at 0.40005 0 270)
			(size 0 0)
			(layers "F.Cu" "F.Mask" "F.Paste")
			(net "SMB_CPU0_4_SCL")
		)
	)
	(footprint ""
		(layer "F.Cu")
		(at 45.212 -171.831 180)
		(property "Reference" "R543"
			(at 0 0 180)
			(layer "F.SilkS")
			(hide yes)
			(effects
				(font
					(size 1.27 1.27)
				)
			)
		)
		(property "Value" ""
			(at 0 0 180)
			(layer "F.Fab")
			(effects
				(font
					(size 1.27 1.27)
				)
			)
		)
		(duplicate_pad_numbers_are_jumpers no)
		(fp_line
			(start 0.7874 0.4064)
			(end -0.7874 0.4064)
			(stroke
				(width 0.1524)
				(type default)
			)
			(layer "F.SilkS")
		)
		(fp_line
			(start 0.7874 -0.4064)
			(end 0.7874 0.4064)
			(stroke
				(width 0.1524)
				(type default)
			)
			(layer "F.SilkS")
		)
		(fp_line
			(start -0.7874 0.4064)
			(end -0.7874 -0.4064)
			(stroke
				(width 0.1524)
				(type default)
			)
			(layer "F.SilkS")
		)
		(fp_line
			(start -0.7874 -0.4064)
			(end 0.7874 -0.4064)
			(stroke
				(width 0.1524)
				(type default)
			)
			(layer "F.SilkS")
		)
		(fp_line
			(start 0.67945 0.3048)
			(end 0.120396 0.3048)
			(stroke
				(width 0.1)
				(type default)
			)
			(layer "F.Fab")
		)
		(fp_line
			(start 0.67945 -0.3048)
			(end 0.67945 0.3048)
			(stroke
				(width 0.1)
				(type default)
			)
			(layer "F.Fab")
		)
		(fp_line
			(start 0.12065 -0.2794)
			(end 0.12065 -0.3048)
			(stroke
				(width 0.1)
				(type default)
			)
			(layer "F.Fab")
		)
		(fp_line
			(start 0.12065 -0.3048)
			(end 0.67945 -0.3048)
			(stroke
				(width 0.1)
				(type default)
			)
			(layer "F.Fab")
		)
		(fp_line
			(start 0.120396 0.3048)
			(end 0.120396 0.2794)
			(stroke
				(width 0.1)
				(type default)
			)
			(layer "F.Fab")
		)
		(fp_line
			(start 0.120396 0.2794)
			(end -0.12065 0.2794)
			(stroke
				(width 0.1)
				(type default)
			)
			(layer "F.Fab")
		)
		(fp_line
			(start -0.12065 0.3048)
			(end -0.67945 0.3048)
			(stroke
				(width 0.1)
				(type default)
			)
			(layer "F.Fab")
		)
		(fp_line
			(start -0.12065 0.2794)
			(end -0.12065 0.3048)
			(stroke
				(width 0.1)
				(type default)
			)
			(layer "F.Fab")
		)
		(fp_line
			(start -0.12065 -0.2794)
			(end 0.12065 -0.2794)
			(stroke
				(width 0.1)
				(type default)
			)
			(layer "F.Fab")
		)
		(fp_line
			(start -0.12065 -0.305054)
			(end -0.12065 -0.2794)
			(stroke
				(width 0.1)
				(type default)
			)
			(layer "F.Fab")
		)
		(fp_line
			(start -0.67945 0.3048)
			(end -0.67945 -0.305054)
			(stroke
				(width 0.1)
				(type default)
			)
			(layer "F.Fab")
		)
		(fp_line
			(start -0.67945 -0.305054)
			(end -0.12065 -0.305054)
			(stroke
				(width 0.1)
				(type default)
			)
			(layer "F.Fab")
		)
		(pad "1" smd circle
			(at -0.40005 0 180)
			(size 0 0)
			(layers "F.Cu" "F.Mask" "F.Paste")
			(net "PVDD11_S3_P1")
		)
		(pad "2" smd circle
			(at 0.40005 0 180)
			(size 0 0)
			(layers "F.Cu" "F.Mask" "F.Paste")
			(net "I3C_0_SPD_DDRAF_CPU1_R_SDA")
		)
	)
	(footprint ""
		(layer "F.Cu")
		(at 89.898982 -53.697378)
		(property "Reference" "PR4523"
			(at 0 0 0)
			(layer "F.SilkS")
			(hide yes)
			(effects
				(font
					(size 1.27 1.27)
				)
			)
		)
		(property "Value" ""
			(at 0 0 0)
			(layer "F.Fab")
			(effects
				(font
					(size 1.27 1.27)
				)
			)
		)
		(duplicate_pad_numbers_are_jumpers no)
		(fp_line
			(start -0.7874 -0.4064)
			(end 0.7874 -0.4064)
			(stroke
				(width 0.1524)
				(type default)
			)
			(layer "F.SilkS")
		)
		(fp_line
			(start -0.7874 0.4064)
			(end -0.7874 -0.4064)
			(stroke
				(width 0.1524)
				(type default)
			)
			(layer "F.SilkS")
		)
		(fp_line
			(start 0.7874 -0.4064)
			(end 0.7874 0.4064)
			(stroke
				(width 0.1524)
				(type default)
			)
			(layer "F.SilkS")
		)
		(fp_line
			(start 0.7874 0.4064)
			(end -0.7874 0.4064)
			(stroke
				(width 0.1524)
				(type default)
			)
			(layer "F.SilkS")
		)
		(fp_line
			(start -0.67945 -0.305054)
			(end -0.12065 -0.305054)
			(stroke
				(width 0.1)
				(type default)
			)
			(layer "F.Fab")
		)
		(fp_line
			(start -0.67945 0.3048)
			(end -0.67945 -0.305054)
			(stroke
				(width 0.1)
				(type default)
			)
			(layer "F.Fab")
		)
		(fp_line
			(start -0.12065 -0.305054)
			(end -0.12065 -0.2794)
			(stroke
				(width 0.1)
				(type default)
			)
			(layer "F.Fab")
		)
		(fp_line
			(start -0.12065 -0.2794)
			(end 0.12065 -0.2794)
			(stroke
				(width 0.1)
				(type default)
			)
			(layer "F.Fab")
		)
		(fp_line
			(start -0.12065 0.2794)
			(end -0.12065 0.3048)
			(stroke
				(width 0.1)
				(type default)
			)
			(layer "F.Fab")
		)
		(fp_line
			(start -0.12065 0.3048)
			(end -0.67945 0.3048)
			(stroke
				(width 0.1)
				(type default)
			)
			(layer "F.Fab")
		)
		(fp_line
			(start 0.120396 0.2794)
			(end -0.12065 0.2794)
			(stroke
				(width 0.1)
				(type default)
			)
			(layer "F.Fab")
		)
		(fp_line
			(start 0.120396 0.3048)
			(end 0.120396 0.2794)
			(stroke
				(width 0.1)
				(type default)
			)
			(layer "F.Fab")
		)
		(fp_line
			(start 0.12065 -0.3048)
			(end 0.67945 -0.3048)
			(stroke
				(width 0.1)
				(type default)
			)
			(layer "F.Fab")
		)
		(fp_line
			(start 0.12065 -0.2794)
			(end 0.12065 -0.3048)
			(stroke
				(width 0.1)
				(type default)
			)
			(layer "F.Fab")
		)
		(fp_line
			(start 0.67945 -0.3048)
			(end 0.67945 0.3048)
			(stroke
				(width 0.1)
				(type default)
			)
			(layer "F.Fab")
		)
		(fp_line
			(start 0.67945 0.3048)
			(end 0.120396 0.3048)
			(stroke
				(width 0.1)
				(type default)
			)
			(layer "F.Fab")
		)
		(pad "1" smd circle
			(at -0.40005 0)
			(size 0 0)
			(layers "F.Cu" "F.Mask" "F.Paste")
			(net "P3V3_OCP_V3_2_R")
		)
		(pad "2" smd circle
			(at 0.40005 0)
			(size 0 0)
			(layers "F.Cu" "F.Mask" "F.Paste")
			(net "P3V3_OCP_GATE_2")
		)
	)
	(footprint ""
		(layer "F.Cu")
		(at 70.32117 -177.540666 90)
		(property "Reference" "PC310_5"
			(at 0 0 90)
			(layer "F.SilkS")
			(hide yes)
			(effects
				(font
					(size 1.27 1.27)
				)
			)
		)
		(property "Value" ""
			(at 0 0 90)
			(layer "F.Fab")
			(effects
				(font
					(size 1.27 1.27)
				)
			)
		)
		(duplicate_pad_numbers_are_jumpers no)
		(fp_line
			(start 0.7874 -0.4064)
			(end 0.7874 0.4064)
			(stroke
				(width 0.1524)
				(type default)
			)
			(layer "F.SilkS")
		)
		(fp_line
			(start -0.7874 -0.4064)
			(end 0.7874 -0.4064)
			(stroke
				(width 0.1524)
				(type default)
			)
			(layer "F.SilkS")
		)
		(fp_line
			(start 0.7874 0.4064)
			(end -0.7874 0.4064)
			(stroke
				(width 0.1524)
				(type default)
			)
			(layer "F.SilkS")
		)
		(fp_line
			(start -0.7874 0.4064)
			(end -0.7874 -0.4064)
			(stroke
				(width 0.1524)
				(type default)
			)
			(layer "F.SilkS")
		)
		(fp_line
			(start -0.12065 -0.305054)
			(end -0.12065 -0.2794)
			(stroke
				(width 0.1)
				(type default)
			)
			(layer "F.Fab")
		)
		(fp_line
			(start -0.67945 -0.305054)
			(end -0.12065 -0.305054)
			(stroke
				(width 0.1)
				(type default)
			)
			(layer "F.Fab")
		)
		(fp_line
			(start 0.67945 -0.3048)
			(end 0.67945 0.3048)
			(stroke
				(width 0.1)
				(type default)
			)
			(layer "F.Fab")
		)
		(fp_line
			(start 0.12065 -0.3048)
			(end 0.67945 -0.3048)
			(stroke
				(width 0.1)
				(type default)
			)
			(layer "F.Fab")
		)
		(fp_line
			(start 0.12065 -0.2794)
			(end 0.12065 -0.3048)
			(stroke
				(width 0.1)
				(type default)
			)
			(layer "F.Fab")
		)
		(fp_line
			(start -0.12065 -0.2794)
			(end 0.12065 -0.2794)
			(stroke
				(width 0.1)
				(type default)
			)
			(layer "F.Fab")
		)
		(fp_line
			(start 0.120396 0.2794)
			(end -0.12065 0.2794)
			(stroke
				(width 0.1)
				(type default)
			)
			(layer "F.Fab")
		)
		(fp_line
			(start -0.12065 0.2794)
			(end -0.12065 0.3048)
			(stroke
				(width 0.1)
				(type default)
			)
			(layer "F.Fab")
		)
		(fp_line
			(start 0.67945 0.3048)
			(end 0.120396 0.3048)
			(stroke
				(width 0.1)
				(type default)
			)
			(layer "F.Fab")
		)
		(fp_line
			(start 0.120396 0.3048)
			(end 0.120396 0.2794)
			(stroke
				(width 0.1)
				(type default)
			)
			(layer "F.Fab")
		)
		(fp_line
			(start -0.12065 0.3048)
			(end -0.67945 0.3048)
			(stroke
				(width 0.1)
				(type default)
			)
			(layer "F.Fab")
		)
		(fp_line
			(start -0.67945 0.3048)
			(end -0.67945 -0.305054)
			(stroke
				(width 0.1)
				(type default)
			)
			(layer "F.Fab")
		)
		(pad "1" smd circle
			(at -0.40005 0 90)
			(size 0 0)
			(layers "F.Cu" "F.Mask" "F.Paste")
			(net "SW_P12V_AUX_PVDDCR_CPU0_P1_FLT")
		)
		(pad "2" smd circle
			(at 0.40005 0 90)
			(size 0 0)
			(layers "F.Cu" "F.Mask" "F.Paste")
			(net "GND")
		)
	)
	(footprint ""
		(layer "F.Cu")
		(at 105.485946 -52.86248 -90)
		(property "Reference" "R6313"
			(at 0 0 270)
			(layer "F.SilkS")
			(hide yes)
			(effects
				(font
					(size 1.27 1.27)
				)
			)
		)
		(property "Value" ""
			(at 0 0 270)
			(layer "F.Fab")
			(effects
				(font
					(size 1.27 1.27)
				)
			)
		)
		(duplicate_pad_numbers_are_jumpers no)
		(fp_line
			(start -0.7874 0.4064)
			(end -0.7874 -0.4064)
			(stroke
				(width 0.1524)
				(type default)
			)
			(layer "F.SilkS")
		)
		(fp_line
			(start 0.7874 0.4064)
			(end -0.7874 0.4064)
			(stroke
				(width 0.1524)
				(type default)
			)
			(layer "F.SilkS")
		)
		(fp_line
			(start -0.7874 -0.4064)
			(end 0.7874 -0.4064)
			(stroke
				(width 0.1524)
				(type default)
			)
			(layer "F.SilkS")
		)
		(fp_line
			(start 0.7874 -0.4064)
			(end 0.7874 0.4064)
			(stroke
				(width 0.1524)
				(type default)
			)
			(layer "F.SilkS")
		)
		(fp_line
			(start -0.67945 0.3048)
			(end -0.67945 -0.305054)
			(stroke
				(width 0.1)
				(type default)
			)
			(layer "F.Fab")
		)
		(fp_line
			(start -0.12065 0.3048)
			(end -0.67945 0.3048)
			(stroke
				(width 0.1)
				(type default)
			)
			(layer "F.Fab")
		)
		(fp_line
			(start 0.120396 0.3048)
			(end 0.120396 0.2794)
			(stroke
				(width 0.1)
				(type default)
			)
			(layer "F.Fab")
		)
		(fp_line
			(start 0.67945 0.3048)
			(end 0.120396 0.3048)
			(stroke
				(width 0.1)
				(type default)
			)
			(layer "F.Fab")
		)
		(fp_line
			(start -0.12065 0.2794)
			(end -0.12065 0.3048)
			(stroke
				(width 0.1)
				(type default)
			)
			(layer "F.Fab")
		)
		(fp_line
			(start 0.120396 0.2794)
			(end -0.12065 0.2794)
			(stroke
				(width 0.1)
				(type default)
			)
			(layer "F.Fab")
		)
		(fp_line
			(start -0.12065 -0.2794)
			(end 0.12065 -0.2794)
			(stroke
				(width 0.1)
				(type default)
			)
			(layer "F.Fab")
		)
		(fp_line
			(start 0.12065 -0.2794)
			(end 0.12065 -0.3048)
			(stroke
				(width 0.1)
				(type default)
			)
			(layer "F.Fab")
		)
		(fp_line
			(start 0.12065 -0.3048)
			(end 0.67945 -0.3048)
			(stroke
				(width 0.1)
				(type default)
			)
			(layer "F.Fab")
		)
		(fp_line
			(start 0.67945 -0.3048)
			(end 0.67945 0.3048)
			(stroke
				(width 0.1)
				(type default)
			)
			(layer "F.Fab")
		)
		(fp_line
			(start -0.67945 -0.305054)
			(end -0.12065 -0.305054)
			(stroke
				(width 0.1)
				(type default)
			)
			(layer "F.Fab")
		)
		(fp_line
			(start -0.12065 -0.305054)
			(end -0.12065 -0.2794)
			(stroke
				(width 0.1)
				(type default)
			)
			(layer "F.Fab")
		)
		(pad "1" smd circle
			(at -0.40005 0 270)
			(size 0 0)
			(layers "F.Cu" "F.Mask" "F.Paste")
			(net "USB_HUB2_TI_OVERCUR2")
		)
		(pad "2" smd circle
			(at 0.40005 0 270)
			(size 0 0)
			(layers "F.Cu" "F.Mask" "F.Paste")
			(net "USB_HUB2_TI_OVERCUR2_MRP_PROG_FUNC5")
		)
	)
)
